(kicad_pcb
	(version 20260206)
	(generator "pcbnew")
	(generator_version "10.0")
	(general
		(thickness 1.6)
		(legacy_teardrops no)
	)
	(paper "A4")
	(title_block
		(title "15969-1a.1015WZS0858.brd")
		(comment 1 "Tioga Pass / footprints 226-232 of 295")
	)
	(layers
		(0 "F.Cu" signal "TOP")
		(4 "In1.Cu" signal "L2GND")
		(6 "In2.Cu" signal "L3")
		(8 "In3.Cu" signal "L4")
		(10 "In4.Cu" signal "L5GND")
		(2 "B.Cu" signal "BOTTOM")
		(9 "F.Adhes" user "F.Adhesive")
		(11 "B.Adhes" user "B.Adhesive")
		(13 "F.Paste" user "Package Geometry/Pastemask Top")
		(15 "B.Paste" user "Package Geometry/Pastemask Bottom")
		(5 "F.SilkS" user "Ref Des/Silkscreen Top")
		(7 "B.SilkS" user "Ref Des/Silkscreen Bottom")
		(1 "F.Mask" user "Board Geometry/Soldermask Top")
		(3 "B.Mask" user "Board Geometry/Soldermask Bottom")
		(17 "Dwgs.User" user "User.Drawings")
		(19 "Cmts.User" user "User.Comments")
		(21 "Eco1.User" user "User.Eco1")
		(23 "Eco2.User" user "User.Eco2")
		(25 "Edge.Cuts" user "Board Geometry/Outline")
		(27 "Margin" user)
		(31 "F.CrtYd" user "Package Geometry/Place Bound Top")
		(29 "B.CrtYd" user "Package Geometry/Place Bound Bottom")
		(35 "F.Fab" user "Ref Des/Assembly Top")
		(33 "B.Fab" user "Ref Des/Assembly Bottom")
	)
	(footprint ""
		(layer "B.Cu")
		(at 20.955 -27.4066)
		(property "Reference" "C50"
			(at 0 0 0)
			(layer "B.SilkS")
			(hide yes)
			(effects
				(font
					(size 1.27 1.27)
				)
				(justify mirror)
			)
		)
		(property "Value" "SCD1U16V2KX-3GP"
			(at -1.1811 -2.7051 0)
			(unlocked yes)
			(layer "B.Fab")
			(hide yes)
			(effects
				(font
					(size 1.016 1.016)
					(thickness 0.1524)
				)
				(justify mirror)
			)
		)
		(property "Device Type" "C402H22"
			(at -1.1811 -4.2291 0)
			(unlocked yes)
			(layer "B.Fab")
			(hide yes)
			(effects
				(font
					(size 1.016 1.016)
					(thickness 0.1524)
				)
				(justify mirror)
			)
		)
		(duplicate_pad_numbers_are_jumpers no)
		(fp_rect
			(start 0.4318 0.9525)
			(end -0.4318 -0.9525)
			(stroke
				(width 0)
				(type default)
			)
			(fill no)
			(layer "B.CrtYd")
		)
		(fp_rect
			(start 0.4318 0.9525)
			(end -0.4318 -0.9525)
			(stroke
				(width 0)
				(type default)
			)
			(fill no)
			(layer "B.Fab")
		)
		(pad "1" smd custom
			(at 0 -0.4445 180)
			(size 0.1524 0.1524)
			(layers "B.Cu" "B.Mask" "B.Paste")
			(net "P3V3_STBY")
			(options
				(clearance outline)
				(anchor circle)
			)
			(primitives
				(gr_poly
					(pts
						(arc
							(start 0.3048 0.2032)
							(mid 0.275042 0.275042)
							(end 0.2032 0.3048)
						)
						(arc
							(start -0.2032 0.3048)
							(mid -0.275042 0.275042)
							(end -0.3048 0.2032)
						)
						(arc
							(start -0.3048 -0.2032)
							(mid -0.275042 -0.275042)
							(end -0.2032 -0.3048)
						)
						(arc
							(start 0.2032 -0.3048)
							(mid 0.275042 -0.275042)
							(end 0.3048 -0.2032)
						)
					)
					(width 0)
					(fill yes)
				)
			)
		)
		(pad "2" smd custom
			(at 0 0.4445 180)
			(size 0.1524 0.1524)
			(layers "B.Cu" "B.Mask" "B.Paste")
			(net "GND")
			(options
				(clearance outline)
				(anchor circle)
			)
			(primitives
				(gr_poly
					(pts
						(arc
							(start 0.3048 0.2032)
							(mid 0.275042 0.275042)
							(end 0.2032 0.3048)
						)
						(arc
							(start -0.2032 0.3048)
							(mid -0.275042 0.275042)
							(end -0.3048 0.2032)
						)
						(arc
							(start -0.3048 -0.2032)
							(mid -0.275042 -0.275042)
							(end -0.2032 -0.3048)
						)
						(arc
							(start 0.2032 -0.3048)
							(mid 0.275042 -0.275042)
							(end 0.3048 -0.2032)
						)
					)
					(width 0)
					(fill yes)
				)
			)
		)
	)
	(footprint ""
		(layer "B.Cu")
		(at 22.352 -9.779 90)
		(property "Reference" "PU1"
			(at 0 0 90)
			(layer "B.SilkS")
			(hide yes)
			(effects
				(font
					(size 1.27 1.27)
				)
				(justify mirror)
			)
		)
		(property "Value" "MPQ8634AGLE-Z-GP"
			(at 4.2799 1.5748 90)
			(unlocked yes)
			(layer "B.Fab")
			(hide yes)
			(effects
				(font
					(size 1.016 1.016)
					(thickness 0.1524)
				)
				(justify mirror)
			)
		)
		(property "Device Type" "QFN21M4030-1H40"
			(at 4.2799 0.0508 90)
			(unlocked yes)
			(layer "B.Fab")
			(hide yes)
			(effects
				(font
					(size 1.016 1.016)
					(thickness 0.1524)
				)
				(justify mirror)
			)
		)
		(duplicate_pad_numbers_are_jumpers no)
		(fp_line
			(start 0 -2.777998)
			(end 0 -2.269998)
			(stroke
				(width 0.1524)
				(type default)
			)
			(layer "B.SilkS")
		)
		(fp_line
			(start 3.0226 -2.5146)
			(end 3.0226 -1.2446)
			(stroke
				(width 0.1524)
				(type default)
			)
			(layer "B.SilkS")
		)
		(fp_line
			(start 1.7526 -2.5146)
			(end 3.0226 -2.5146)
			(stroke
				(width 0.1524)
				(type default)
			)
			(layer "B.SilkS")
		)
		(fp_line
			(start 3.526282 -0.299974)
			(end 2.764282 -0.299974)
			(stroke
				(width 0.1524)
				(type default)
			)
			(layer "B.SilkS")
		)
		(fp_line
			(start -2.764282 0.299974)
			(end -3.526282 0.299974)
			(stroke
				(width 0.1524)
				(type default)
			)
			(layer "B.SilkS")
		)
		(fp_line
			(start 3.0226 1.2446)
			(end 3.0226 2.5146)
			(stroke
				(width 0.1524)
				(type default)
			)
			(layer "B.SilkS")
		)
		(fp_line
			(start -3.0226 1.2446)
			(end -3.0226 2.5146)
			(stroke
				(width 0.1524)
				(type default)
			)
			(layer "B.SilkS")
		)
		(fp_line
			(start 3.0226 2.5146)
			(end 1.7526 2.5146)
			(stroke
				(width 0.1524)
				(type default)
			)
			(layer "B.SilkS")
		)
		(fp_line
			(start -3.0226 2.5146)
			(end -1.7526 2.5146)
			(stroke
				(width 0.1524)
				(type default)
			)
			(layer "B.SilkS")
		)
		(fp_line
			(start 0 2.777998)
			(end 0 2.269998)
			(stroke
				(width 0.1524)
				(type default)
			)
			(layer "B.SilkS")
		)
		(fp_poly
			(pts
				(xy -1.7526 -2.5146) (xy -3.0226 -2.5146) (xy -3.0226 -1.2446)
			)
			(stroke
				(width 0)
				(type default)
			)
			(fill yes)
			(layer "B.SilkS")
		)
		(fp_rect
			(start 1.9939 1.4986)
			(end -1.9939 -1.4986)
			(stroke
				(width 0)
				(type default)
			)
			(fill no)
			(layer "B.CrtYd")
		)
		(fp_poly
			(pts
				(xy 3.0226 2.5146) (xy 3.0226 -2.5146) (xy -3.0226 -2.5146) (xy -3.0226 -0.00635) (xy -1.9939 -0.00635)
				(xy -1.9939 -1.4986) (xy 1.9939 -1.4986) (xy 1.9939 1.4986) (xy -1.9939 1.4986) (xy -1.9939 0.00635)
				(xy -3.0226 0.00635) (xy -3.0226 2.5146)
			)
			(stroke
				(width 0)
				(type default)
			)
			(fill no)
			(layer "B.CrtYd")
		)
		(fp_rect
			(start 3.0226 2.5146)
			(end -3.0226 -2.5146)
			(stroke
				(width 0)
				(type default)
			)
			(fill no)
			(layer "B.Fab")
		)
		(pad "1" smd rect
			(at -1.700022 -1.380998 270)
			(size 0.3048 1.3208)
			(drill
				(offset 0 -0.0254)
			)
			(layers "B.Cu" "B.Mask" "B.Paste")
			(net "P3V3_BST")
		)
		(pad "2" smd rect
			(at -1.199896 -1.380998 270)
			(size 0.2032 1.27)
			(layers "B.Cu" "B.Mask" "B.Paste")
			(net "AGND_P3V3")
		)
		(pad "3" smd rect
			(at -0.8001 -1.380998 270)
			(size 0.2032 1.27)
			(layers "B.Cu" "B.Mask" "B.Paste")
			(net "P3V3_CS")
		)
		(pad "4" smd rect
			(at -0.40005 -1.380998 270)
			(size 0.2032 1.27)
			(layers "B.Cu" "B.Mask" "B.Paste")
			(net "P3V3_MODE")
		)
		(pad "5" smd rect
			(at 0 -1.380998 270)
			(size 0.2032 1.27)
			(layers "B.Cu" "B.Mask" "B.Paste")
			(net "P3V3_TRK")
		)
		(pad "6" smd rect
			(at 0.40005 -1.380998 270)
			(size 0.2032 1.27)
			(layers "B.Cu" "B.Mask" "B.Paste")
			(net "GND")
		)
		(pad "7" smd rect
			(at 0.8001 -1.380998 270)
			(size 0.2032 1.27)
			(layers "B.Cu" "B.Mask" "B.Paste")
			(net "P3V3_FB")
		)
		(pad "8" smd rect
			(at 1.199896 -1.380998 270)
			(size 0.2032 1.27)
			(layers "B.Cu" "B.Mask" "B.Paste")
			(net "P3V3_EN")
		)
		(pad "9" smd rect
			(at 1.700022 -1.380998 270)
			(size 0.3048 1.27)
			(layers "B.Cu" "B.Mask" "B.Paste")
			(net "P3V3_PG")
		)
		(pad "10" smd rect
			(at 1.380236 -0.299974 270)
			(size 2.2606 0.3556)
			(layers "B.Cu" "B.Mask" "B.Paste")
			(net "P3V3_VIN")
		)
		(pad "11" smd custom
			(at 1.700022 1.380998 270)
			(size 0.3175 0.3175)
			(layers "B.Cu" "B.Mask" "B.Paste")
			(net "GND")
			(options
				(clearance outline)
				(anchor circle)
			)
			(primitives
				(gr_poly
					(pts
						(xy -1.272032 0.034798) (xy -1.272032 -0.635) (xy -1.576832 -0.635) (xy -1.576832 0.635) (xy 1.577086 0.635)
						(xy 1.577086 -0.635) (xy 1.373886 -0.635) (xy 1.373886 0.034798) (xy 1.17729 0.034798) (xy 1.17729 -0.635)
						(xy 0.97409 -0.635) (xy 0.97409 0.034798) (xy 0.77724 0.034798) (xy 0.77724 -0.635) (xy 0.57404 -0.635)
						(xy 0.57404 0.034798) (xy 0.37719 0.034798) (xy 0.37719 -0.635) (xy 0.17399 -0.635) (xy 0.17399 0.034798)
						(xy -0.02286 0.034798) (xy -0.02286 -0.635) (xy -0.22606 -0.635) (xy -0.22606 0.034798) (xy -0.42291 0.034798)
						(xy -0.42291 -0.635) (xy -0.62611 -0.635) (xy -0.62611 0.034798) (xy -0.822706 0.034798) (xy -0.822706 -0.635)
						(xy -1.025906 -0.635) (xy -1.025906 0.034798)
					)
					(width 0)
					(fill yes)
				)
			)
		)
		(pad "12" smd rect
			(at 1.199896 1.380998 270)
			(size 0.0254 0.0254)
			(layers "B.Cu" "B.Mask" "B.Paste")
			(net "GND")
		)
		(pad "13" smd rect
			(at 0.8001 1.380998 270)
			(size 0.0254 0.0254)
			(layers "B.Cu" "B.Mask" "B.Paste")
			(net "GND")
		)
		(pad "14" smd rect
			(at 0.40005 1.380998 270)
			(size 0.0254 0.0254)
			(layers "B.Cu" "B.Mask" "B.Paste")
			(net "GND")
		)
		(pad "15" smd rect
			(at 0 1.380998 270)
			(size 0.0254 0.0254)
			(layers "B.Cu" "B.Mask" "B.Paste")
			(net "GND")
		)
		(pad "16" smd rect
			(at -0.40005 1.380998 270)
			(size 0.0254 0.0254)
			(layers "B.Cu" "B.Mask" "B.Paste")
			(net "GND")
		)
		(pad "17" smd rect
			(at -0.8001 1.380998 270)
			(size 0.0254 0.0254)
			(layers "B.Cu" "B.Mask" "B.Paste")
			(net "GND")
		)
		(pad "18" smd rect
			(at -1.199896 1.380998 270)
			(size 0.0254 0.0254)
			(layers "B.Cu" "B.Mask" "B.Paste")
			(net "GND")
		)
		(pad "19" smd rect
			(at -1.700022 1.380998 270)
			(size 0.3048 1.27)
			(layers "B.Cu" "B.Mask" "B.Paste")
			(net "P3V3_VCC")
		)
		(pad "20" smd rect
			(at -1.380236 0.299974 270)
			(size 2.2606 0.3556)
			(layers "B.Cu" "B.Mask" "B.Paste")
			(net "P3V3_SW")
		)
		(pad "21" smd rect
			(at -1.380236 -0.299974 270)
			(size 2.2606 0.3556)
			(layers "B.Cu" "B.Mask" "B.Paste")
			(net "P3V3_VIN")
		)
	)
	(footprint ""
		(layer "B.Cu")
		(at 16.2687 -12.4587 -90)
		(property "Reference" "PC10"
			(at 0 0 90)
			(layer "B.SilkS")
			(hide yes)
			(effects
				(font
					(size 1.27 1.27)
				)
				(justify mirror)
			)
		)
		(property "Value" "SC270P50V2KX-1GP"
			(at -1.1811 -2.7051 270)
			(unlocked yes)
			(layer "B.Fab")
			(hide yes)
			(effects
				(font
					(size 1.016 1.016)
					(thickness 0.1524)
				)
				(justify mirror)
			)
		)
		(property "Device Type" "C402H22"
			(at -1.1811 -4.2291 270)
			(unlocked yes)
			(layer "B.Fab")
			(hide yes)
			(effects
				(font
					(size 1.016 1.016)
					(thickness 0.1524)
				)
				(justify mirror)
			)
		)
		(duplicate_pad_numbers_are_jumpers no)
		(fp_rect
			(start 0.4318 0.9525)
			(end -0.4318 -0.9525)
			(stroke
				(width 0)
				(type default)
			)
			(fill no)
			(layer "B.CrtYd")
		)
		(fp_rect
			(start 0.4318 0.9525)
			(end -0.4318 -0.9525)
			(stroke
				(width 0)
				(type default)
			)
			(fill no)
			(layer "B.Fab")
		)
		(pad "1" smd custom
			(at 0 -0.4445 90)
			(size 0.1524 0.1524)
			(layers "B.Cu" "B.Mask" "B.Paste")
			(net "P3V3_FB")
			(options
				(clearance outline)
				(anchor circle)
			)
			(primitives
				(gr_poly
					(pts
						(arc
							(start 0.3048 0.2032)
							(mid 0.275042 0.275042)
							(end 0.2032 0.3048)
						)
						(arc
							(start -0.2032 0.3048)
							(mid -0.275042 0.275042)
							(end -0.3048 0.2032)
						)
						(arc
							(start -0.3048 -0.2032)
							(mid -0.275042 -0.275042)
							(end -0.2032 -0.3048)
						)
						(arc
							(start 0.2032 -0.3048)
							(mid 0.275042 -0.275042)
							(end 0.3048 -0.2032)
						)
					)
					(width 0)
					(fill yes)
				)
			)
		)
		(pad "2" smd custom
			(at 0 0.4445 90)
			(size 0.1524 0.1524)
			(layers "B.Cu" "B.Mask" "B.Paste")
			(net "P3V3_VFB_R")
			(options
				(clearance outline)
				(anchor circle)
			)
			(primitives
				(gr_poly
					(pts
						(arc
							(start 0.3048 0.2032)
							(mid 0.275042 0.275042)
							(end 0.2032 0.3048)
						)
						(arc
							(start -0.2032 0.3048)
							(mid -0.275042 0.275042)
							(end -0.3048 0.2032)
						)
						(arc
							(start -0.3048 -0.2032)
							(mid -0.275042 -0.275042)
							(end -0.2032 -0.3048)
						)
						(arc
							(start 0.2032 -0.3048)
							(mid 0.275042 -0.275042)
							(end 0.3048 -0.2032)
						)
					)
					(width 0)
					(fill yes)
				)
			)
		)
	)
	(footprint ""
		(layer "B.Cu")
		(at 23.1394 -13.7922 90)
		(property "Reference" "PC2"
			(at 0 0 90)
			(layer "B.SilkS")
			(hide yes)
			(effects
				(font
					(size 1.27 1.27)
				)
				(justify mirror)
			)
		)
		(property "Value" "SC22U16V5MX-4-GP"
			(at 0.0762 -6.1214 90)
			(unlocked yes)
			(layer "B.Fab")
			(hide yes)
			(effects
				(font
					(size 1.016 1.016)
					(thickness 0.1524)
				)
				(justify mirror)
			)
		)
		(property "Device Type" "C805H58"
			(at 0.0762 -8.1534 90)
			(unlocked yes)
			(layer "B.Fab")
			(hide yes)
			(effects
				(font
					(size 1.016 1.016)
					(thickness 0.1524)
				)
				(justify mirror)
			)
		)
		(duplicate_pad_numbers_are_jumpers no)
		(fp_line
			(start -0.635 0)
			(end 0.635 0)
			(stroke
				(width 0.508)
				(type default)
			)
			(layer "B.SilkS")
		)
		(fp_rect
			(start 0.9652 1.778)
			(end -0.9652 -1.778)
			(stroke
				(width 0)
				(type default)
			)
			(fill no)
			(layer "B.CrtYd")
		)
		(fp_poly
			(pts
				(xy 0.9652 -1.778) (xy -0.9652 -1.778) (xy -0.9652 1.778) (xy 0.9652 1.778)
			)
			(stroke
				(width 0)
				(type default)
			)
			(fill no)
			(layer "B.Fab")
		)
		(pad "1" smd rect
			(at 0 -0.9652 270)
			(size 1.397 1.143)
			(layers "B.Cu" "B.Mask" "B.Paste")
			(net "P3V3_VIN")
		)
		(pad "2" smd rect
			(at 0 0.9652 270)
			(size 1.397 1.143)
			(layers "B.Cu" "B.Mask" "B.Paste")
			(net "GND")
		)
	)
	(footprint ""
		(layer "B.Cu")
		(at 121.2596 -28.7782)
		(property "Reference" "TP82"
			(at 0 0 0)
			(layer "B.SilkS")
			(hide yes)
			(effects
				(font
					(size 1.27 1.27)
				)
				(justify mirror)
			)
		)
		(property "Value" "TPAD24"
			(at 0 -1.6129 0)
			(unlocked yes)
			(layer "B.Fab")
			(hide yes)
			(effects
				(font
					(size 1.016 1.016)
					(thickness 0.1524)
				)
				(justify mirror)
			)
		)
		(property "Device Type" "TPAD24"
			(at 0 -3.1369 0)
			(unlocked yes)
			(layer "B.Fab")
			(hide yes)
			(effects
				(font
					(size 1.016 1.016)
					(thickness 0.1524)
				)
				(justify mirror)
			)
		)
		(duplicate_pad_numbers_are_jumpers no)
		(fp_poly
			(pts
				(arc
					(start 0.3048 0)
					(mid -0.3048 0)
					(end 0.3048 0)
				)
			)
			(stroke
				(width 0)
				(type default)
			)
			(fill no)
			(layer "B.CrtYd")
		)
		(fp_poly
			(pts
				(arc
					(start 0.6096 0)
					(mid -0.6096 0)
					(end 0.6096 0)
				)
			)
			(stroke
				(width 0)
				(type default)
			)
			(fill no)
			(layer "B.Fab")
		)
		(pad "1" smd circle
			(at 0 0 180)
			(size 0.6096 0.6096)
			(layers "B.Cu" "B.Mask" "B.Paste")
			(net "TP_USB_OCS_N1")
		)
	)
	(footprint ""
		(layer "B.Cu")
		(at 125.7554 -25.146 90)
		(property "Reference" "RU20"
			(at 0 0 90)
			(layer "B.SilkS")
			(hide yes)
			(effects
				(font
					(size 1.27 1.27)
				)
				(justify mirror)
			)
		)
		(property "Value" "100KR2F-L1-GP"
			(at -0.064008 -3.993896 90)
			(unlocked yes)
			(layer "B.Fab")
			(hide yes)
			(effects
				(font
					(size 1.016 1.016)
					(thickness 0.1524)
				)
				(justify mirror)
			)
		)
		(property "Device Type" "R402H16"
			(at -0.064008 -5.517896 90)
			(unlocked yes)
			(layer "B.Fab")
			(hide yes)
			(effects
				(font
					(size 1.016 1.016)
					(thickness 0.1524)
				)
				(justify mirror)
			)
		)
		(duplicate_pad_numbers_are_jumpers no)
		(fp_line
			(start 0.508 -0.9398)
			(end 0.508 0.9398)
			(stroke
				(width 0.1524)
				(type default)
			)
			(layer "B.SilkS")
		)
		(fp_line
			(start -0.508 -0.9398)
			(end 0.508 -0.9398)
			(stroke
				(width 0.1524)
				(type default)
			)
			(layer "B.SilkS")
		)
		(fp_rect
			(start 0.508 0.9398)
			(end -0.508 -0.9398)
			(stroke
				(width 0)
				(type default)
			)
			(fill no)
			(layer "B.CrtYd")
		)
		(fp_rect
			(start 0.508 0.9398)
			(end -0.508 -0.9398)
			(stroke
				(width 0)
				(type default)
			)
			(fill no)
			(layer "B.Fab")
		)
		(pad "1" smd custom
			(at 0 -0.4445 270)
			(size 0.1397 0.1397)
			(layers "B.Cu" "B.Mask" "B.Paste")
			(net "P3V3_USB_HUB")
			(options
				(clearance outline)
				(anchor circle)
			)
			(primitives
				(gr_poly
					(pts
						(arc
							(start -0.1778 0.2794)
							(mid -0.249642 0.249642)
							(end -0.2794 0.1778)
						)
						(arc
							(start -0.2794 -0.1778)
							(mid -0.249642 -0.249642)
							(end -0.1778 -0.2794)
						)
						(arc
							(start 0.1778 -0.2794)
							(mid 0.249642 -0.249642)
							(end 0.2794 -0.1778)
						)
						(arc
							(start 0.2794 0.1778)
							(mid 0.249642 0.249642)
							(end 0.1778 0.2794)
						)
					)
					(width 0)
					(fill yes)
				)
			)
		)
		(pad "2" smd custom
			(at 0 0.4445 270)
			(size 0.1397 0.1397)
			(layers "B.Cu" "B.Mask" "B.Paste")
			(net "CFG_SEL1")
			(options
				(clearance outline)
				(anchor circle)
			)
			(primitives
				(gr_poly
					(pts
						(arc
							(start -0.1778 0.2794)
							(mid -0.249642 0.249642)
							(end -0.2794 0.1778)
						)
						(arc
							(start -0.2794 -0.1778)
							(mid -0.249642 -0.249642)
							(end -0.1778 -0.2794)
						)
						(arc
							(start 0.1778 -0.2794)
							(mid 0.249642 -0.249642)
							(end 0.2794 -0.1778)
						)
						(arc
							(start 0.2794 0.1778)
							(mid 0.249642 0.249642)
							(end 0.1778 0.2794)
						)
					)
					(width 0)
					(fill yes)
				)
			)
		)
	)
	(footprint ""
		(layer "B.Cu")
		(at 25.1206 -31.9532 180)
		(property "Reference" "C89"
			(at 0 0 0)
			(layer "B.SilkS")
			(hide yes)
			(effects
				(font
					(size 1.27 1.27)
				)
				(justify mirror)
			)
		)
		(property "Value" "SC22U16V5MX-4-GP"
			(at 0.0762 -6.1214 180)
			(unlocked yes)
			(layer "B.Fab")
			(hide yes)
			(effects
				(font
					(size 1.016 1.016)
					(thickness 0.1524)
				)
				(justify mirror)
			)
		)
		(property "Device Type" "C805H58"
			(at 0.0762 -8.1534 180)
			(unlocked yes)
			(layer "B.Fab")
			(hide yes)
			(effects
				(font
					(size 1.016 1.016)
					(thickness 0.1524)
				)
				(justify mirror)
			)
		)
		(duplicate_pad_numbers_are_jumpers no)
		(fp_line
			(start -0.635 0)
			(end 0.635 0)
			(stroke
				(width 0.508)
				(type default)
			)
			(layer "B.SilkS")
		)
		(fp_rect
			(start 0.9652 1.778)
			(end -0.9652 -1.778)
			(stroke
				(width 0)
				(type default)
			)
			(fill no)
			(layer "B.CrtYd")
		)
		(fp_poly
			(pts
				(xy 0.9652 -1.778) (xy -0.9652 -1.778) (xy -0.9652 1.778) (xy 0.9652 1.778)
			)
			(stroke
				(width 0)
				(type default)
			)
			(fill no)
			(layer "B.Fab")
		)
		(pad "1" smd rect
			(at 0 -0.9652)
			(size 1.397 1.143)
			(layers "B.Cu" "B.Mask" "B.Paste")
			(net "P12V_ATX")
		)
		(pad "2" smd rect
			(at 0 0.9652)
			(size 1.397 1.143)
			(layers "B.Cu" "B.Mask" "B.Paste")
			(net "GND")
		)
	)
)
